# SCM (Grand Teton) — schematic netlist excerpt (pin names and nets, part order shuffled) for the footprints in the layout excerpt that follows; sources: Cadence DE-HDL packaged netlist, KiCad conversion of 12092022_DA0F0TMDCD0_F0T_Management_Board_D_brd_V3_OCP.brd

R18  Q_RES  0 5% CHIP  pkg 0402LF  page 23 : A = P5V_AUX ; B = BMC_DDC_BUF_PWR
C279  Q_CAP  0.1UF 25V 10% X7R  pkg 0402  page 17 : A = ADCVREFEXT1 ; B = GND

(kicad_pcb
	(version 20260206)
	(generator "pcbnew")
	(generator_version "10.0")
	(general
		(thickness 1.6)
		(legacy_teardrops no)
	)
	(paper "A4")
	(title_block
		(title "12092022_DA0F0TMDCD0_F0T_Management_Board_D_brd_V3_OCP.brd")
		(comment 1 "Grand Teton / footprints 1215-1216 of 1440")
	)
	(layers
		(0 "F.Cu" signal "TOP")
		(4 "In1.Cu" signal "GND")
		(6 "In2.Cu" signal "IN1")
		(8 "In3.Cu" signal "GND1")
		(10 "In4.Cu" signal "IN2")
		(12 "In5.Cu" signal "VCC")
		(14 "In6.Cu" signal "VCC1")
		(16 "In7.Cu" signal "IN3")
		(18 "In8.Cu" signal "GND2")
		(20 "In9.Cu" signal "IN4")
		(22 "In10.Cu" signal "GND3")
		(2 "B.Cu" signal "BOTTOM")
		(9 "F.Adhes" user "F.Adhesive")
		(11 "B.Adhes" user "B.Adhesive")
		(13 "F.Paste" user "Package Geometry/Pastemask Top")
		(15 "B.Paste" user "Package Geometry/Pastemask Bottom")
		(5 "F.SilkS" user "Ref Des/Silkscreen Top")
		(7 "B.SilkS" user "Ref Des/Silkscreen Bottom")
		(1 "F.Mask" user "Board Geometry/Soldermask Top")
		(3 "B.Mask" user "Board Geometry/Soldermask Bottom")
		(17 "Dwgs.User" user "User.Drawings")
		(19 "Cmts.User" user "User.Comments")
		(21 "Eco1.User" user "User.Eco1")
		(23 "Eco2.User" user "User.Eco2")
		(25 "Edge.Cuts" user "Board Geometry/Outline")
		(27 "Margin" user)
		(31 "F.CrtYd" user "Package Geometry/Place Bound Top")
		(29 "B.CrtYd" user "Package Geometry/Place Bound Bottom")
		(35 "F.Fab" user "Ref Des/Assembly Top")
		(33 "B.Fab" user "Ref Des/Assembly Bottom")
	)
	(footprint ""
		(layer "B.Cu")
		(at 52.384452 -60.134246 90)
		(property "Reference" "C279"
			(at 0 0 90)
			(layer "B.SilkS")
			(hide yes)
			(effects
				(font
					(size 1.27 1.27)
				)
				(justify mirror)
			)
		)
		(property "Value" ""
			(at 0 0 90)
			(layer "B.Fab")
			(effects
				(font
					(size 1.27 1.27)
				)
				(justify mirror)
			)
		)
		(duplicate_pad_numbers_are_jumpers no)
		(fp_line
			(start 0.7874 -0.4064)
			(end -0.7874 -0.4064)
			(stroke
				(width 0.1524)
				(type default)
			)
			(layer "B.SilkS")
		)
		(fp_line
			(start -0.7874 -0.4064)
			(end -0.7874 0.4064)
			(stroke
				(width 0.1524)
				(type default)
			)
			(layer "B.SilkS")
		)
		(fp_line
			(start 0.7874 0.4064)
			(end 0.7874 -0.4064)
			(stroke
				(width 0.1524)
				(type default)
			)
			(layer "B.SilkS")
		)
		(fp_line
			(start -0.7874 0.4064)
			(end 0.7874 0.4064)
			(stroke
				(width 0.1524)
				(type default)
			)
			(layer "B.SilkS")
		)
		(fp_line
			(start 0.67945 -0.305054)
			(end 0.12065 -0.305054)
			(stroke
				(width 0.1)
				(type default)
			)
			(layer "B.Fab")
		)
		(fp_line
			(start 0.12065 -0.305054)
			(end 0.12065 -0.2794)
			(stroke
				(width 0.1)
				(type default)
			)
			(layer "B.Fab")
		)
		(fp_line
			(start -0.12065 -0.3048)
			(end -0.67945 -0.3048)
			(stroke
				(width 0.1)
				(type default)
			)
			(layer "B.Fab")
		)
		(fp_line
			(start -0.67945 -0.3048)
			(end -0.67945 0.3048)
			(stroke
				(width 0.1)
				(type default)
			)
			(layer "B.Fab")
		)
		(fp_line
			(start 0.12065 -0.2794)
			(end -0.12065 -0.2794)
			(stroke
				(width 0.1)
				(type default)
			)
			(layer "B.Fab")
		)
		(fp_line
			(start -0.12065 -0.2794)
			(end -0.12065 -0.3048)
			(stroke
				(width 0.1)
				(type default)
			)
			(layer "B.Fab")
		)
		(fp_line
			(start 0.12065 0.2794)
			(end 0.12065 0.3048)
			(stroke
				(width 0.1)
				(type default)
			)
			(layer "B.Fab")
		)
		(fp_line
			(start -0.120396 0.2794)
			(end 0.12065 0.2794)
			(stroke
				(width 0.1)
				(type default)
			)
			(layer "B.Fab")
		)
		(fp_line
			(start 0.67945 0.3048)
			(end 0.67945 -0.305054)
			(stroke
				(width 0.1)
				(type default)
			)
			(layer "B.Fab")
		)
		(fp_line
			(start 0.12065 0.3048)
			(end 0.67945 0.3048)
			(stroke
				(width 0.1)
				(type default)
			)
			(layer "B.Fab")
		)
		(fp_line
			(start -0.120396 0.3048)
			(end -0.120396 0.2794)
			(stroke
				(width 0.1)
				(type default)
			)
			(layer "B.Fab")
		)
		(fp_line
			(start -0.67945 0.3048)
			(end -0.120396 0.3048)
			(stroke
				(width 0.1)
				(type default)
			)
			(layer "B.Fab")
		)
		(pad "1" smd circle
			(at 0.40005 0 270)
			(size 0 0)
			(layers "B.Cu" "B.Mask" "B.Paste")
			(net "ADCVREFEXT1")
		)
		(pad "2" smd circle
			(at -0.40005 0 270)
			(size 0 0)
			(layers "B.Cu" "B.Mask" "B.Paste")
			(net "GND")
		)
	)
	(footprint ""
		(layer "B.Cu")
		(at 45.5676 -4.1148 -90)
		(property "Reference" "R18"
			(at 0 0 90)
			(layer "B.SilkS")
			(hide yes)
			(effects
				(font
					(size 1.27 1.27)
				)
				(justify mirror)
			)
		)
		(property "Value" ""
			(at 0 0 90)
			(layer "B.Fab")
			(effects
				(font
					(size 1.27 1.27)
				)
				(justify mirror)
			)
		)
		(duplicate_pad_numbers_are_jumpers no)
		(fp_line
			(start -0.7874 0.4064)
			(end 0.7874 0.4064)
			(stroke
				(width 0.1524)
				(type default)
			)
			(layer "B.SilkS")
		)
		(fp_line
			(start 0.7874 0.4064)
			(end 0.7874 -0.4064)
			(stroke
				(width 0.1524)
				(type default)
			)
			(layer "B.SilkS")
		)
		(fp_line
			(start -0.7874 -0.4064)
			(end -0.7874 0.4064)
			(stroke
				(width 0.1524)
				(type default)
			)
			(layer "B.SilkS")
		)
		(fp_line
			(start 0.7874 -0.4064)
			(end -0.7874 -0.4064)
			(stroke
				(width 0.1524)
				(type default)
			)
			(layer "B.SilkS")
		)
		(fp_line
			(start -0.67945 0.3048)
			(end -0.120396 0.3048)
			(stroke
				(width 0.1)
				(type default)
			)
			(layer "B.Fab")
		)
		(fp_line
			(start -0.120396 0.3048)
			(end -0.120396 0.2794)
			(stroke
				(width 0.1)
				(type default)
			)
			(layer "B.Fab")
		)
		(fp_line
			(start 0.12065 0.3048)
			(end 0.67945 0.3048)
			(stroke
				(width 0.1)
				(type default)
			)
			(layer "B.Fab")
		)
		(fp_line
			(start 0.67945 0.3048)
			(end 0.67945 -0.305054)
			(stroke
				(width 0.1)
				(type default)
			)
			(layer "B.Fab")
		)
		(fp_line
			(start -0.120396 0.2794)
			(end 0.12065 0.2794)
			(stroke
				(width 0.1)
				(type default)
			)
			(layer "B.Fab")
		)
		(fp_line
			(start 0.12065 0.2794)
			(end 0.12065 0.3048)
			(stroke
				(width 0.1)
				(type default)
			)
			(layer "B.Fab")
		)
		(fp_line
			(start -0.12065 -0.2794)
			(end -0.12065 -0.3048)
			(stroke
				(width 0.1)
				(type default)
			)
			(layer "B.Fab")
		)
		(fp_line
			(start 0.12065 -0.2794)
			(end -0.12065 -0.2794)
			(stroke
				(width 0.1)
				(type default)
			)
			(layer "B.Fab")
		)
		(fp_line
			(start -0.67945 -0.3048)
			(end -0.67945 0.3048)
			(stroke
				(width 0.1)
				(type default)
			)
			(layer "B.Fab")
		)
		(fp_line
			(start -0.12065 -0.3048)
			(end -0.67945 -0.3048)
			(stroke
				(width 0.1)
				(type default)
			)
			(layer "B.Fab")
		)
		(fp_line
			(start 0.12065 -0.305054)
			(end 0.12065 -0.2794)
			(stroke
				(width 0.1)
				(type default)
			)
			(layer "B.Fab")
		)
		(fp_line
			(start 0.67945 -0.305054)
			(end 0.12065 -0.305054)
			(stroke
				(width 0.1)
				(type default)
			)
			(layer "B.Fab")
		)
		(pad "1" smd circle
			(at 0.40005 0 90)
			(size 0 0)
			(layers "B.Cu" "B.Mask" "B.Paste")
			(net "P5V_AUX")
		)
		(pad "2" smd circle
			(at -0.40005 0 90)
			(size 0 0)
			(layers "B.Cu" "B.Mask" "B.Paste")
			(net "BMC_DDC_BUF_PWR")
		)
	)
)
